(kicad_pcb
	(version 20241229)
	(generator "pcbnew")
	(generator_version "9.0")
	(general
		(thickness 1.599998)
		(legacy_teardrops no)
	)
	(paper "A4")
	(title_block
		(date "2023-02-12")
		(rev "1.1.5")
		(comment 9 "footprints 158-163 of 473")
	)
	(layers
		(0 "F.Cu" signal)
		(4 "In1.Cu" power "In1.GND")
		(6 "In2.Cu" signal)
		(8 "In3.Cu" power "In3.GND")
		(10 "In4.Cu" power "In4.VCC")
		(12 "In5.Cu" signal)
		(14 "In6.Cu" power "In6.VCC")
		(2 "B.Cu" signal)
		(9 "F.Adhes" user "F.Adhesive")
		(11 "B.Adhes" user "B.Adhesive")
		(13 "F.Paste" user)
		(15 "B.Paste" user)
		(5 "F.SilkS" user "F.Silkscreen")
		(7 "B.SilkS" user "B.Silkscreen")
		(1 "F.Mask" user)
		(3 "B.Mask" user)
		(17 "Dwgs.User" user "User.Drawings")
		(19 "Cmts.User" user "User.Comments")
		(21 "Eco1.User" user "User.Eco1")
		(23 "Eco2.User" user "User.Eco2")
		(25 "Edge.Cuts" user)
		(27 "Margin" user)
		(31 "F.CrtYd" user "F.Courtyard")
		(29 "B.CrtYd" user "B.Courtyard")
		(35 "F.Fab" user)
		(33 "B.Fab" user)
	)
	(footprint "antmicro-footprints:LED_0603_1608Metric_G"
		(layer "F.Cu")
		(at 200.586328 64.020008 180)
		(descr "LED SMD 0603 Green")
		(tags "LED SMD 0603 Green")
		(property "Reference" "D2"
			(at 0.786328 0.620008 180)
			(layer "F.SilkS")
			(effects
				(font
					(size 0.7 0.7)
					(thickness 0.15)
				)
				(justify left bottom)
			)
		)
		(property "Value" "LED_G_0603_KP-1608CGCK"
			(at 0 1.6 180)
			(layer "F.Fab")
			(effects
				(font
					(size 0.7 0.7)
					(thickness 0.15)
				)
				(justify left bottom)
			)
		)
		(property "Author" "Antmicro"
			(at 401.172656 128.040016 0)
			(layer "F.Fab")
			(hide yes)
			(effects
				(font
					(size 1 1)
					(thickness 0.15)
				)
			)
		)
		(property "License" "Apache-2.0"
			(at 401.172656 128.040016 0)
			(layer "F.Fab")
			(hide yes)
			(effects
				(font
					(size 1 1)
					(thickness 0.15)
				)
			)
		)
		(property "MPN" "KP-1608CGCK"
			(at 401.172656 128.040016 0)
			(layer "F.Fab")
			(hide yes)
			(effects
				(font
					(size 1 1)
					(thickness 0.15)
				)
			)
		)
		(property "Manufacturer" "Kingbright"
			(at 401.172656 128.040016 0)
			(layer "F.Fab")
			(hide yes)
			(effects
				(font
					(size 1 1)
					(thickness 0.15)
				)
			)
		)
		(sheetname "Interfaces")
		(sheetfile "interfaces.kicad_sch")
		(attr smd)
		(fp_line
			(start 1.25 0.32)
			(end 1.25 -0.32)
			(stroke
				(width 0.15)
				(type solid)
			)
			(layer "F.SilkS")
		)
		(fp_line
			(start 0.093672 -8e-06)
			(end 0.293672 -8e-06)
			(stroke
				(width 0.1)
				(type solid)
			)
			(layer "F.SilkS")
		)
		(fp_line
			(start 0.093672 -8e-06)
			(end -0.106328 0.199992)
			(stroke
				(width 0.1)
				(type solid)
			)
			(layer "F.SilkS")
		)
		(fp_line
			(start 0.093672 -0.200008)
			(end 0.093672 0.199992)
			(stroke
				(width 0.1)
				(type solid)
			)
			(layer "F.SilkS")
		)
		(fp_line
			(start -0.106328 -8e-06)
			(end -0.29 0)
			(stroke
				(width 0.1)
				(type solid)
			)
			(layer "F.SilkS")
		)
		(fp_line
			(start -0.106328 -0.200008)
			(end 0.093672 -8e-06)
			(stroke
				(width 0.1)
				(type solid)
			)
			(layer "F.SilkS")
		)
		(fp_line
			(start -0.106328 -0.200008)
			(end -0.106328 0.199992)
			(stroke
				(width 0.1)
				(type solid)
			)
			(layer "F.SilkS")
		)
		(fp_line
			(start -0.27 0.351)
			(end 0.27 0.351)
			(stroke
				(width 0.15)
				(type solid)
			)
			(layer "F.SilkS")
		)
		(fp_line
			(start -0.27 -0.35)
			(end 0.27 -0.35)
			(stroke
				(width 0.15)
				(type solid)
			)
			(layer "F.SilkS")
		)
		(fp_rect
			(start 1.26 0.65)
			(end -1.26 -0.65)
			(stroke
				(width 0.05)
				(type solid)
			)
			(fill no)
			(layer "F.CrtYd")
		)
		(fp_line
			(start 0.199 0.202)
			(end 0.199 -0.1)
			(stroke
				(width 0.15)
				(type solid)
			)
			(layer "F.Fab")
		)
		(fp_line
			(start 0.199 0)
			(end 0.597 0)
			(stroke
				(width 0.15)
				(type solid)
			)
			(layer "F.Fab")
		)
		(fp_line
			(start 0.199 -0.2)
			(end 0.199 -0.1)
			(stroke
				(width 0.15)
				(type solid)
			)
			(layer "F.Fab")
		)
		(fp_line
			(start 0.101 0)
			(end -0.201 -0.2)
			(stroke
				(width 0.15)
				(type solid)
			)
			(layer "F.Fab")
		)
		(fp_line
			(start -0.201 0.202)
			(end 0.101 0)
			(stroke
				(width 0.15)
				(type solid)
			)
			(layer "F.Fab")
		)
		(fp_line
			(start -0.201 0)
			(end -0.201 0.202)
			(stroke
				(width 0.15)
				(type solid)
			)
			(layer "F.Fab")
		)
		(fp_line
			(start -0.201 -0.2)
			(end -0.201 0)
			(stroke
				(width 0.15)
				(type solid)
			)
			(layer "F.Fab")
		)
		(fp_line
			(start -0.599 0)
			(end -0.201 0)
			(stroke
				(width 0.15)
				(type solid)
			)
			(layer "F.Fab")
		)
		(fp_rect
			(start -0.848 -0.4)
			(end 0.85 0.402)
			(stroke
				(width 0.15)
				(type solid)
			)
			(fill no)
			(layer "F.Fab")
		)
		(pad "1" smd rect
			(at -0.75 0)
			(size 0.8 0.8)
			(layers "F.Cu" "F.Mask" "F.Paste")
			(net 459 "3V3_SYS")
			(pinfunction "1")
			(pintype "passive")
		)
		(pad "2" smd rect
			(at 0.75 0)
			(size 0.8 0.8)
			(layers "F.Cu" "F.Mask" "F.Paste")
			(net 72 "Net-(D2-Pad2)")
			(pinfunction "2")
			(pintype "passive")
		)
	)
	(footprint "antmicro-footprints:R_0402_1005Metric"
		(layer "F.Cu")
		(at 205.286328 79.320008 -90)
		(descr "Resistor SMD 0402")
		(tags "resistor SMD 0402")
		(property "Reference" "R62"
			(at 3.079992 -0.413672 270)
			(layer "F.SilkS")
			(effects
				(font
					(size 0.7 0.7)
					(thickness 0.15)
				)
				(justify left bottom)
			)
		)
		(property "Value" "R_0R_0402"
			(at 0 1.4 270)
			(layer "F.Fab")
			(effects
				(font
					(size 0.7 0.7)
					(thickness 0.15)
				)
				(justify left bottom)
			)
		)
		(property "Description" "0R resistor in 0402 package with unspecified tolerance"
			(at 0 0 270)
			(layer "F.Fab")
			(hide yes)
			(effects
				(font
					(size 1.27 1.27)
					(thickness 0.15)
				)
			)
		)
		(property "Author" "Antmicro"
			(at 125.96632 284.606336 0)
			(layer "F.Fab")
			(hide yes)
			(effects
				(font
					(size 1 1)
					(thickness 0.15)
				)
			)
		)
		(property "Current" "1A"
			(at 125.96632 284.606336 0)
			(layer "F.Fab")
			(hide yes)
			(effects
				(font
					(size 1 1)
					(thickness 0.15)
				)
			)
		)
		(property "License" "Apache-2.0"
			(at 125.96632 284.606336 0)
			(layer "F.Fab")
			(hide yes)
			(effects
				(font
					(size 1 1)
					(thickness 0.15)
				)
			)
		)
		(property "MPN" "ERJ2GE0R00X"
			(at 125.96632 284.606336 0)
			(layer "F.Fab")
			(hide yes)
			(effects
				(font
					(size 1 1)
					(thickness 0.15)
				)
			)
		)
		(property "Manufacturer" "Panasonic"
			(at 125.96632 284.606336 0)
			(layer "F.Fab")
			(hide yes)
			(effects
				(font
					(size 1 1)
					(thickness 0.15)
				)
			)
		)
		(property "Tolerance" ""
			(at 125.96632 284.606336 0)
			(layer "F.Fab")
			(hide yes)
			(effects
				(font
					(size 1 1)
					(thickness 0.15)
				)
			)
		)
		(property "Val" "0R"
			(at 125.96632 284.606336 0)
			(layer "F.Fab")
			(hide yes)
			(effects
				(font
					(size 1 1)
					(thickness 0.15)
				)
			)
		)
		(sheetname "Config SPI flash")
		(sheetfile "config-spi.kicad_sch")
		(attr smd)
		(fp_rect
			(start -0.93 -0.47)
			(end 0.93 0.47)
			(stroke
				(width 0.05)
				(type solid)
			)
			(fill no)
			(layer "F.CrtYd")
		)
		(fp_rect
			(start -0.5 -0.25)
			(end 0.5 0.25)
			(stroke
				(width 0.15)
				(type solid)
			)
			(fill no)
			(layer "F.Fab")
		)
		(pad "1" smd roundrect
			(at -0.485 0 270)
			(size 0.59 0.64)
			(layers "F.Cu" "F.Mask" "F.Paste")
			(roundrect_rratio 0.25)
			(net 19 "MODE0")
			(pintype "passive")
		)
		(pad "2" smd roundrect
			(at 0.485 0 270)
			(size 0.59 0.64)
			(layers "F.Cu" "F.Mask" "F.Paste")
			(roundrect_rratio 0.25)
			(net 459 "3V3_SYS")
			(pintype "passive")
		)
	)
	(footprint "antmicro-footprints:R_0402_1005Metric"
		(layer "F.Cu")
		(at 206.386328 79.320008 -90)
		(descr "Resistor SMD 0402")
		(tags "resistor SMD 0402")
		(property "Reference" "R63"
			(at 3.079992 -0.413672 270)
			(layer "F.SilkS")
			(effects
				(font
					(size 0.7 0.7)
					(thickness 0.15)
				)
				(justify left bottom)
			)
		)
		(property "Value" "R_0R_0402"
			(at 0 1.4 270)
			(layer "F.Fab")
			(effects
				(font
					(size 0.7 0.7)
					(thickness 0.15)
				)
				(justify left bottom)
			)
		)
		(property "Description" "0R resistor in 0402 package with unspecified tolerance"
			(at 0 0 270)
			(layer "F.Fab")
			(hide yes)
			(effects
				(font
					(size 1.27 1.27)
					(thickness 0.15)
				)
			)
		)
		(property "Author" "Antmicro"
			(at 127.06632 285.706336 0)
			(layer "F.Fab")
			(hide yes)
			(effects
				(font
					(size 1 1)
					(thickness 0.15)
				)
			)
		)
		(property "Current" "1A"
			(at 127.06632 285.706336 0)
			(layer "F.Fab")
			(hide yes)
			(effects
				(font
					(size 1 1)
					(thickness 0.15)
				)
			)
		)
		(property "License" "Apache-2.0"
			(at 127.06632 285.706336 0)
			(layer "F.Fab")
			(hide yes)
			(effects
				(font
					(size 1 1)
					(thickness 0.15)
				)
			)
		)
		(property "MPN" "ERJ2GE0R00X"
			(at 127.06632 285.706336 0)
			(layer "F.Fab")
			(hide yes)
			(effects
				(font
					(size 1 1)
					(thickness 0.15)
				)
			)
		)
		(property "Manufacturer" "Panasonic"
			(at 127.06632 285.706336 0)
			(layer "F.Fab")
			(hide yes)
			(effects
				(font
					(size 1 1)
					(thickness 0.15)
				)
			)
		)
		(property "Tolerance" ""
			(at 127.06632 285.706336 0)
			(layer "F.Fab")
			(hide yes)
			(effects
				(font
					(size 1 1)
					(thickness 0.15)
				)
			)
		)
		(property "Val" "0R"
			(at 127.06632 285.706336 0)
			(layer "F.Fab")
			(hide yes)
			(effects
				(font
					(size 1 1)
					(thickness 0.15)
				)
			)
		)
		(sheetname "Config SPI flash")
		(sheetfile "config-spi.kicad_sch")
		(attr exclude_from_pos_files exclude_from_bom dnp)
		(fp_rect
			(start -0.93 -0.47)
			(end 0.93 0.47)
			(stroke
				(width 0.05)
				(type solid)
			)
			(fill no)
			(layer "F.CrtYd")
		)
		(fp_rect
			(start -0.5 -0.25)
			(end 0.5 0.25)
			(stroke
				(width 0.15)
				(type solid)
			)
			(fill no)
			(layer "F.Fab")
		)
		(pad "1" smd roundrect
			(at -0.485 0 270)
			(size 0.59 0.64)
			(layers "F.Cu" "F.Mask" "F.Paste")
			(roundrect_rratio 0.25)
			(net 19 "MODE0")
			(pintype "passive")
		)
		(pad "2" smd roundrect
			(at 0.485 0 270)
			(size 0.59 0.64)
			(layers "F.Cu" "F.Mask" "F.Paste")
			(roundrect_rratio 0.25)
			(net 5 "GND")
			(pintype "passive")
		)
	)
	(footprint "antmicro-footprints:SC70-3"
		(layer "F.Cu")
		(at 199.686328 84.45)
		(property "Reference" "Q6"
			(at -0.786328 -1.35 0)
			(layer "F.SilkS")
			(effects
				(font
					(size 0.7 0.7)
					(thickness 0.15)
				)
				(justify left bottom)
			)
		)
		(property "Value" "BSS138PW"
			(at 0 2.3 0)
			(layer "F.Fab")
			(effects
				(font
					(size 0.7 0.7)
					(thickness 0.15)
				)
				(justify left bottom)
			)
		)
		(property "Description" "60 V, 320 mA N-channel enhancement mode Trench MOSFET, SC-70-3 aka SOT-323 package"
			(at 0 0 0)
			(layer "F.Fab")
			(hide yes)
			(effects
				(font
					(size 1.27 1.27)
					(thickness 0.15)
				)
			)
		)
		(property "Author" "Antmicro"
			(at 0 0 0)
			(layer "F.Fab")
			(hide yes)
			(effects
				(font
					(size 1 1)
					(thickness 0.15)
				)
			)
		)
		(property "License" "Apache-2.0"
			(at 0 0 0)
			(layer "F.Fab")
			(hide yes)
			(effects
				(font
					(size 1 1)
					(thickness 0.15)
				)
			)
		)
		(property "MPN" "BSS138PW"
			(at 0 0 0)
			(layer "F.Fab")
			(hide yes)
			(effects
				(font
					(size 1 1)
					(thickness 0.15)
				)
			)
		)
		(property "Manufacturer" "Nexperia"
			(at 0 0 0)
			(layer "F.Fab")
			(hide yes)
			(effects
				(font
					(size 1 1)
					(thickness 0.15)
				)
			)
		)
		(sheetname "Config SPI flash")
		(sheetfile "config-spi.kicad_sch")
		(attr smd)
		(fp_line
			(start -0.3 -1)
			(end 0.627 -0.999)
			(stroke
				(width 0.15)
				(type solid)
			)
			(layer "F.SilkS")
		)
		(fp_line
			(start -0.3 1)
			(end 0.627 1.001)
			(stroke
				(width 0.15)
				(type solid)
			)
			(layer "F.SilkS")
		)
		(fp_line
			(start 0.627 -0.6)
			(end 0.627 -0.999)
			(stroke
				(width 0.15)
				(type solid)
			)
			(layer "F.SilkS")
		)
		(fp_line
			(start 0.627 0.6)
			(end 0.627 1.001)
			(stroke
				(width 0.15)
				(type solid)
			)
			(layer "F.SilkS")
		)
		(fp_line
			(start -1.4 1)
			(end -1.4 -1)
			(stroke
				(width 0.05)
				(type solid)
			)
			(layer "F.CrtYd")
		)
		(fp_line
			(start -0.9 -1.3)
			(end -0.9 -1)
			(stroke
				(width 0.05)
				(type solid)
			)
			(layer "F.CrtYd")
		)
		(fp_line
			(start -0.9 -1.3)
			(end 0.9 -1.3)
			(stroke
				(width 0.05)
				(type solid)
			)
			(layer "F.CrtYd")
		)
		(fp_line
			(start -0.9 -1)
			(end -1.4 -1)
			(stroke
				(width 0.05)
				(type solid)
			)
			(layer "F.CrtYd")
		)
		(fp_line
			(start -0.9 1)
			(end -1.4 1)
			(stroke
				(width 0.05)
				(type solid)
			)
			(layer "F.CrtYd")
		)
		(fp_line
			(start -0.9 1.3)
			(end -0.9 1)
			(stroke
				(width 0.05)
				(type solid)
			)
			(layer "F.CrtYd")
		)
		(fp_line
			(start 0.9 -1.3)
			(end 0.9 -0.4)
			(stroke
				(width 0.05)
				(type solid)
			)
			(layer "F.CrtYd")
		)
		(fp_line
			(start 0.9 -0.4)
			(end 1.4 -0.4)
			(stroke
				(width 0.05)
				(type solid)
			)
			(layer "F.CrtYd")
		)
		(fp_line
			(start 0.9 0.4)
			(end 0.9 1.3)
			(stroke
				(width 0.05)
				(type solid)
			)
			(layer "F.CrtYd")
		)
		(fp_line
			(start 0.9 1.3)
			(end -0.9 1.3)
			(stroke
				(width 0.05)
				(type solid)
			)
			(layer "F.CrtYd")
		)
		(fp_line
			(start 1.4 -0.4)
			(end 1.4 0.4)
			(stroke
				(width 0.05)
				(type solid)
			)
			(layer "F.CrtYd")
		)
		(fp_line
			(start 1.4 0.4)
			(end 0.9 0.4)
			(stroke
				(width 0.05)
				(type solid)
			)
			(layer "F.CrtYd")
		)
		(fp_rect
			(start -0.623 -0.999)
			(end 0.627 1.001)
			(stroke
				(width 0.15)
				(type solid)
			)
			(fill no)
			(layer "F.Fab")
		)
		(pad "1" smd rect
			(at -0.95 -0.65 90)
			(size 0.6 0.8)
			(layers "F.Cu" "F.Mask" "F.Paste")
			(net 21 "DONE")
			(pinfunction "G")
			(pintype "bidirectional")
		)
		(pad "2" smd rect
			(at -0.95 0.65 90)
			(size 0.6 0.8)
			(layers "F.Cu" "F.Mask" "F.Paste")
			(net 5 "GND")
			(pinfunction "S")
			(pintype "bidirectional")
		)
		(pad "3" smd rect
			(at 0.95 0 90)
			(size 0.6 0.8)
			(layers "F.Cu" "F.Mask" "F.Paste")
			(net 232 "Net-(Q6-D)")
			(pinfunction "D")
			(pintype "bidirectional")
		)
	)
	(footprint "antmicro-footprints:C_0402_1005Metric"
		(layer "F.Cu")
		(at 205.486328 103.774306 90)
		(descr "Capacitor SMD 0402")
		(tags "capacitor SMD 0402")
		(property "Reference" "C105"
			(at -1.025694 2.413672 90)
			(layer "F.SilkS")
			(effects
				(font
					(size 0.7 0.7)
					(thickness 0.15)
				)
				(justify left bottom)
			)
		)
		(property "Value" "C_470n_0402"
			(at 0 1.4 90)
			(layer "F.Fab")
			(effects
				(font
					(size 0.7 0.7)
					(thickness 0.15)
				)
				(justify left bottom)
			)
		)
		(property "Description" " "
			(at 0 0 90)
			(layer "F.Fab")
			(hide yes)
			(effects
				(font
					(size 1.27 1.27)
					(thickness 0.15)
				)
			)
		)
		(property "Author" "Antmicro"
			(at 309.260634 -101.712022 0)
			(layer "F.Fab")
			(hide yes)
			(effects
				(font
					(size 1 1)
					(thickness 0.15)
				)
			)
		)
		(property "Dielectric" ""
			(at 309.260634 -101.712022 0)
			(layer "F.Fab")
			(hide yes)
			(effects
				(font
					(size 1 1)
					(thickness 0.15)
				)
			)
		)
		(property "License" "Apache-2.0"
			(at 309.260634 -101.712022 0)
			(layer "F.Fab")
			(hide yes)
			(effects
				(font
					(size 1 1)
					(thickness 0.15)
				)
			)
		)
		(property "MPN" "C1005X5R1E474M050BB"
			(at 309.260634 -101.712022 0)
			(layer "F.Fab")
			(hide yes)
			(effects
				(font
					(size 1 1)
					(thickness 0.15)
				)
			)
		)
		(property "Manufacturer" "TDK"
			(at 309.260634 -101.712022 0)
			(layer "F.Fab")
			(hide yes)
			(effects
				(font
					(size 1 1)
					(thickness 0.15)
				)
			)
		)
		(property "Val" "470n"
			(at 309.260634 -101.712022 0)
			(layer "F.Fab")
			(hide yes)
			(effects
				(font
					(size 1 1)
					(thickness 0.15)
				)
			)
		)
		(property "Voltage" ""
			(at 309.260634 -101.712022 0)
			(layer "F.Fab")
			(hide yes)
			(effects
				(font
					(size 1 1)
					(thickness 0.15)
				)
			)
		)
		(sheetname "Ethernet")
		(sheetfile "ethernet.kicad_sch")
		(attr smd)
		(fp_rect
			(start -0.94 -0.47)
			(end 0.94 0.47)
			(stroke
				(width 0.05)
				(type solid)
			)
			(fill no)
			(layer "F.CrtYd")
		)
		(fp_rect
			(start -0.499 -0.249)
			(end 0.499 0.249)
			(stroke
				(width 0.15)
				(type solid)
			)
			(fill no)
			(layer "F.Fab")
		)
		(pad "1" smd roundrect
			(at -0.484 0 90)
			(size 0.59 0.64)
			(layers "F.Cu" "F.Mask" "F.Paste")
			(roundrect_rratio 0.25)
			(net 459 "3V3_SYS")
			(pintype "passive")
		)
		(pad "2" smd roundrect
			(at 0.484 0 90)
			(size 0.59 0.64)
			(layers "F.Cu" "F.Mask" "F.Paste")
			(roundrect_rratio 0.25)
			(net 5 "GND")
			(pintype "passive")
		)
	)
	(footprint "antmicro-footprints:C_0402_1005Metric"
		(layer "F.Cu")
		(at 206.586328 103.774306 90)
		(descr "Capacitor SMD 0402")
		(tags "capacitor SMD 0402")
		(property "Reference" "C117"
			(at -1.025694 2.413672 90)
			(layer "F.SilkS")
			(effects
				(font
					(size 0.7 0.7)
					(thickness 0.15)
				)
				(justify left bottom)
			)
		)
		(property "Value" "C_10n_0402"
			(at 0 1.4 90)
			(layer "F.Fab")
			(effects
				(font
					(size 0.7 0.7)
					(thickness 0.15)
				)
				(justify left bottom)
			)
		)
		(property "Description" " "
			(at 0 0 90)
			(layer "F.Fab")
			(hide yes)
			(effects
				(font
					(size 1.27 1.27)
					(thickness 0.15)
				)
			)
		)
		(property "Author" "Antmicro"
			(at 310.360634 -102.812022 0)
			(layer "F.Fab")
			(hide yes)
			(effects
				(font
					(size 1 1)
					(thickness 0.15)
				)
			)
		)
		(property "Dielectric" "X7R"
			(at 310.360634 -102.812022 0)
			(layer "F.Fab")
			(hide yes)
			(effects
				(font
					(size 1 1)
					(thickness 0.15)
				)
			)
		)
		(property "License" "Apache-2.0"
			(at 310.360634 -102.812022 0)
			(layer "F.Fab")
			(hide yes)
			(effects
				(font
					(size 1 1)
					(thickness 0.15)
				)
			)
		)
		(property "MPN" "GRM155R71H103KA88D"
			(at 310.360634 -102.812022 0)
			(layer "F.Fab")
			(hide yes)
			(effects
				(font
					(size 1 1)
					(thickness 0.15)
				)
			)
		)
		(property "Manufacturer" "Murata"
			(at 310.360634 -102.812022 0)
			(layer "F.Fab")
			(hide yes)
			(effects
				(font
					(size 1 1)
					(thickness 0.15)
				)
			)
		)
		(property "Val" "10n"
			(at 310.360634 -102.812022 0)
			(layer "F.Fab")
			(hide yes)
			(effects
				(font
					(size 1 1)
					(thickness 0.15)
				)
			)
		)
		(property "Voltage" "50V"
			(at 310.360634 -102.812022 0)
			(layer "F.Fab")
			(hide yes)
			(effects
				(font
					(size 1 1)
					(thickness 0.15)
				)
			)
		)
		(sheetname "Ethernet")
		(sheetfile "ethernet.kicad_sch")
		(attr smd)
		(fp_rect
			(start -0.94 -0.47)
			(end 0.94 0.47)
			(stroke
				(width 0.05)
				(type solid)
			)
			(fill no)
			(layer "F.CrtYd")
		)
		(fp_rect
			(start -0.499 -0.249)
			(end 0.499 0.249)
			(stroke
				(width 0.15)
				(type solid)
			)
			(fill no)
			(layer "F.Fab")
		)
		(pad "1" smd roundrect
			(at -0.484 0 90)
			(size 0.59 0.64)
			(layers "F.Cu" "F.Mask" "F.Paste")
			(roundrect_rratio 0.25)
			(net 459 "3V3_SYS")
			(pintype "passive")
		)
		(pad "2" smd roundrect
			(at 0.484 0 90)
			(size 0.59 0.64)
			(layers "F.Cu" "F.Mask" "F.Paste")
			(roundrect_rratio 0.25)
			(net 5 "GND")
			(pintype "passive")
		)
	)
)
